(kicad_pcb
	(version 20260206)
	(generator "pcbnew")
	(generator_version "10.0")
	(general
		(thickness 1.6)
		(legacy_teardrops no)
	)
	(paper "A4")
	(title_block
		(title "03242023_DA0F0TMBIJ0_F0T_Motherboard_J_brd_V01_OCP.brd")
		(comment 1 "Grand Teton / footprints 4797-4802 of 6105")
	)
	(layers
		(0 "F.Cu" signal "TOP")
		(4 "In1.Cu" signal "GND")
		(6 "In2.Cu" signal "IN1")
		(8 "In3.Cu" signal "GND1")
		(10 "In4.Cu" signal "IN2")
		(12 "In5.Cu" signal "GND2")
		(14 "In6.Cu" signal "IN3")
		(16 "In7.Cu" signal "GND3")
		(18 "In8.Cu" signal "VCC")
		(20 "In9.Cu" signal "VCC1")
		(22 "In10.Cu" signal "GND4")
		(24 "In11.Cu" signal "IN4")
		(26 "In12.Cu" signal "GND5")
		(28 "In13.Cu" signal "IN5")
		(30 "In14.Cu" signal "GND6")
		(32 "In15.Cu" signal "IN6")
		(34 "In16.Cu" signal "GND7")
		(2 "B.Cu" signal "BOTTOM")
		(9 "F.Adhes" user "F.Adhesive")
		(11 "B.Adhes" user "B.Adhesive")
		(13 "F.Paste" user "Package Geometry/Pastemask Top")
		(15 "B.Paste" user "Package Geometry/Pastemask Bottom")
		(5 "F.SilkS" user "Ref Des/Silkscreen Top")
		(7 "B.SilkS" user "Ref Des/Silkscreen Bottom")
		(1 "F.Mask" user "Board Geometry/Soldermask Top")
		(3 "B.Mask" user "Board Geometry/Soldermask Bottom")
		(17 "Dwgs.User" user "User.Drawings")
		(19 "Cmts.User" user "User.Comments")
		(21 "Eco1.User" user "User.Eco1")
		(23 "Eco2.User" user "User.Eco2")
		(25 "Edge.Cuts" user "Board Geometry/Outline")
		(27 "Margin" user)
		(31 "F.CrtYd" user "Package Geometry/Place Bound Top")
		(29 "B.CrtYd" user "Package Geometry/Place Bound Bottom")
		(35 "F.Fab" user "Ref Des/Assembly Top")
		(33 "B.Fab" user "Ref Des/Assembly Bottom")
	)
	(footprint ""
		(layer "B.Cu")
		(at 187.34913 -13.60043 -90)
		(property "Reference" "R596"
			(at 0 0 90)
			(layer "B.SilkS")
			(hide yes)
			(effects
				(font
					(size 1.27 1.27)
				)
				(justify mirror)
			)
		)
		(property "Value" ""
			(at 0 0 90)
			(layer "B.Fab")
			(effects
				(font
					(size 1.27 1.27)
				)
				(justify mirror)
			)
		)
		(duplicate_pad_numbers_are_jumpers no)
		(fp_line
			(start -0.7874 0.4064)
			(end 0.7874 0.4064)
			(stroke
				(width 0.1524)
				(type default)
			)
			(layer "B.SilkS")
		)
		(fp_line
			(start 0.7874 0.4064)
			(end 0.7874 -0.4064)
			(stroke
				(width 0.1524)
				(type default)
			)
			(layer "B.SilkS")
		)
		(fp_line
			(start -0.7874 -0.4064)
			(end -0.7874 0.4064)
			(stroke
				(width 0.1524)
				(type default)
			)
			(layer "B.SilkS")
		)
		(fp_line
			(start 0.7874 -0.4064)
			(end -0.7874 -0.4064)
			(stroke
				(width 0.1524)
				(type default)
			)
			(layer "B.SilkS")
		)
		(fp_line
			(start -0.67945 0.3048)
			(end -0.120396 0.3048)
			(stroke
				(width 0.1)
				(type default)
			)
			(layer "B.Fab")
		)
		(fp_line
			(start -0.120396 0.3048)
			(end -0.120396 0.2794)
			(stroke
				(width 0.1)
				(type default)
			)
			(layer "B.Fab")
		)
		(fp_line
			(start 0.12065 0.3048)
			(end 0.67945 0.3048)
			(stroke
				(width 0.1)
				(type default)
			)
			(layer "B.Fab")
		)
		(fp_line
			(start 0.67945 0.3048)
			(end 0.67945 -0.305054)
			(stroke
				(width 0.1)
				(type default)
			)
			(layer "B.Fab")
		)
		(fp_line
			(start -0.120396 0.2794)
			(end 0.12065 0.2794)
			(stroke
				(width 0.1)
				(type default)
			)
			(layer "B.Fab")
		)
		(fp_line
			(start 0.12065 0.2794)
			(end 0.12065 0.3048)
			(stroke
				(width 0.1)
				(type default)
			)
			(layer "B.Fab")
		)
		(fp_line
			(start -0.12065 -0.2794)
			(end -0.12065 -0.3048)
			(stroke
				(width 0.1)
				(type default)
			)
			(layer "B.Fab")
		)
		(fp_line
			(start 0.12065 -0.2794)
			(end -0.12065 -0.2794)
			(stroke
				(width 0.1)
				(type default)
			)
			(layer "B.Fab")
		)
		(fp_line
			(start -0.67945 -0.3048)
			(end -0.67945 0.3048)
			(stroke
				(width 0.1)
				(type default)
			)
			(layer "B.Fab")
		)
		(fp_line
			(start -0.12065 -0.3048)
			(end -0.67945 -0.3048)
			(stroke
				(width 0.1)
				(type default)
			)
			(layer "B.Fab")
		)
		(fp_line
			(start 0.12065 -0.305054)
			(end 0.12065 -0.2794)
			(stroke
				(width 0.1)
				(type default)
			)
			(layer "B.Fab")
		)
		(fp_line
			(start 0.67945 -0.305054)
			(end 0.12065 -0.305054)
			(stroke
				(width 0.1)
				(type default)
			)
			(layer "B.Fab")
		)
		(pad "1" smd circle
			(at 0.40005 0 90)
			(size 0 0)
			(layers "B.Cu" "B.Mask" "B.Paste")
			(net "I3C_SPD_DDREFGH_CPU0_BMC_R_SDA")
		)
		(pad "2" smd circle
			(at -0.40005 0 90)
			(size 0 0)
			(layers "B.Cu" "B.Mask" "B.Paste")
			(net "I3C_SPD_DDREFGH_CPU0_BMC_SDA")
		)
	)
	(footprint ""
		(layer "B.Cu")
		(at 333.935578 -185.76925 180)
		(property "Reference" "R20"
			(at 0 0 0)
			(layer "B.SilkS")
			(hide yes)
			(effects
				(font
					(size 1.27 1.27)
				)
				(justify mirror)
			)
		)
		(property "Value" ""
			(at 0 0 0)
			(layer "B.Fab")
			(effects
				(font
					(size 1.27 1.27)
				)
				(justify mirror)
			)
		)
		(duplicate_pad_numbers_are_jumpers no)
		(fp_line
			(start 0.7874 0.4064)
			(end 0.7874 -0.4064)
			(stroke
				(width 0.1524)
				(type default)
			)
			(layer "B.SilkS")
		)
		(fp_line
			(start 0.7874 -0.4064)
			(end -0.7874 -0.4064)
			(stroke
				(width 0.1524)
				(type default)
			)
			(layer "B.SilkS")
		)
		(fp_line
			(start -0.7874 0.4064)
			(end 0.7874 0.4064)
			(stroke
				(width 0.1524)
				(type default)
			)
			(layer "B.SilkS")
		)
		(fp_line
			(start -0.7874 -0.4064)
			(end -0.7874 0.4064)
			(stroke
				(width 0.1524)
				(type default)
			)
			(layer "B.SilkS")
		)
		(fp_line
			(start 0.67945 0.3048)
			(end 0.67945 -0.305054)
			(stroke
				(width 0.1)
				(type default)
			)
			(layer "B.Fab")
		)
		(fp_line
			(start 0.67945 -0.305054)
			(end 0.12065 -0.305054)
			(stroke
				(width 0.1)
				(type default)
			)
			(layer "B.Fab")
		)
		(fp_line
			(start 0.12065 0.3048)
			(end 0.67945 0.3048)
			(stroke
				(width 0.1)
				(type default)
			)
			(layer "B.Fab")
		)
		(fp_line
			(start 0.12065 0.2794)
			(end 0.12065 0.3048)
			(stroke
				(width 0.1)
				(type default)
			)
			(layer "B.Fab")
		)
		(fp_line
			(start 0.12065 -0.2794)
			(end -0.12065 -0.2794)
			(stroke
				(width 0.1)
				(type default)
			)
			(layer "B.Fab")
		)
		(fp_line
			(start 0.12065 -0.305054)
			(end 0.12065 -0.2794)
			(stroke
				(width 0.1)
				(type default)
			)
			(layer "B.Fab")
		)
		(fp_line
			(start -0.120396 0.3048)
			(end -0.120396 0.2794)
			(stroke
				(width 0.1)
				(type default)
			)
			(layer "B.Fab")
		)
		(fp_line
			(start -0.120396 0.2794)
			(end 0.12065 0.2794)
			(stroke
				(width 0.1)
				(type default)
			)
			(layer "B.Fab")
		)
		(fp_line
			(start -0.12065 -0.2794)
			(end -0.12065 -0.3048)
			(stroke
				(width 0.1)
				(type default)
			)
			(layer "B.Fab")
		)
		(fp_line
			(start -0.12065 -0.3048)
			(end -0.67945 -0.3048)
			(stroke
				(width 0.1)
				(type default)
			)
			(layer "B.Fab")
		)
		(fp_line
			(start -0.67945 0.3048)
			(end -0.120396 0.3048)
			(stroke
				(width 0.1)
				(type default)
			)
			(layer "B.Fab")
		)
		(fp_line
			(start -0.67945 -0.3048)
			(end -0.67945 0.3048)
			(stroke
				(width 0.1)
				(type default)
			)
			(layer "B.Fab")
		)
		(pad "1" smd circle
			(at 0.40005 0)
			(size 0 0)
			(layers "B.Cu" "B.Mask" "B.Paste")
			(net "DBP_CPU_MBP0_GTL_N")
		)
		(pad "2" smd circle
			(at -0.40005 0)
			(size 0 0)
			(layers "B.Cu" "B.Mask" "B.Paste")
			(net "FM_PCH_TRIGGER0_N")
		)
	)
	(footprint ""
		(layer "B.Cu")
		(at 65.067688 -250.792996 90)
		(property "Reference" "C453"
			(at 0 0 90)
			(layer "B.SilkS")
			(hide yes)
			(effects
				(font
					(size 1.27 1.27)
				)
				(justify mirror)
			)
		)
		(property "Value" ""
			(at 0 0 90)
			(layer "B.Fab")
			(effects
				(font
					(size 1.27 1.27)
				)
				(justify mirror)
			)
		)
		(duplicate_pad_numbers_are_jumpers no)
		(fp_line
			(start 1.524 -0.762)
			(end -1.524 -0.762)
			(stroke
				(width 0.1524)
				(type default)
			)
			(layer "B.SilkS")
		)
		(fp_line
			(start -1.524 -0.762)
			(end -1.524 0.762)
			(stroke
				(width 0.1524)
				(type default)
			)
			(layer "B.SilkS")
		)
		(fp_line
			(start 1.524 0.762)
			(end 1.524 -0.762)
			(stroke
				(width 0.1524)
				(type default)
			)
			(layer "B.SilkS")
		)
		(fp_line
			(start -1.524 0.762)
			(end 1.524 0.762)
			(stroke
				(width 0.1524)
				(type default)
			)
			(layer "B.SilkS")
		)
		(fp_line
			(start 1.1049 -0.724916)
			(end 1.1049 0.724916)
			(stroke
				(width 0.1)
				(type default)
			)
			(layer "B.Fab")
		)
		(fp_line
			(start -1.1049 -0.724916)
			(end 1.1049 -0.724916)
			(stroke
				(width 0.1)
				(type default)
			)
			(layer "B.Fab")
		)
		(fp_line
			(start 1.1049 0.724916)
			(end -1.1049 0.724916)
			(stroke
				(width 0.1)
				(type default)
			)
			(layer "B.Fab")
		)
		(fp_line
			(start -1.1049 0.724916)
			(end -1.1049 -0.724916)
			(stroke
				(width 0.1)
				(type default)
			)
			(layer "B.Fab")
		)
		(pad "1" smd rect
			(at 0.889 0 90)
			(size 1.016 1.27)
			(layers "B.Cu" "B.Mask" "B.Paste")
			(net "PVCCFA_EHV_FIVRA_CPU1")
		)
		(pad "2" smd rect
			(at -0.889 0 90)
			(size 1.016 1.27)
			(layers "B.Cu" "B.Mask" "B.Paste")
			(net "GND")
		)
	)
	(footprint ""
		(layer "B.Cu")
		(at 383.650998 -80.09255 90)
		(property "Reference" "R2358"
			(at 0 0 90)
			(layer "B.SilkS")
			(hide yes)
			(effects
				(font
					(size 1.27 1.27)
				)
				(justify mirror)
			)
		)
		(property "Value" ""
			(at 0 0 90)
			(layer "B.Fab")
			(effects
				(font
					(size 1.27 1.27)
				)
				(justify mirror)
			)
		)
		(duplicate_pad_numbers_are_jumpers no)
		(fp_line
			(start 0.7874 -0.4064)
			(end -0.7874 -0.4064)
			(stroke
				(width 0.1524)
				(type default)
			)
			(layer "B.SilkS")
		)
		(fp_line
			(start -0.7874 -0.4064)
			(end -0.7874 0.4064)
			(stroke
				(width 0.1524)
				(type default)
			)
			(layer "B.SilkS")
		)
		(fp_line
			(start 0.7874 0.4064)
			(end 0.7874 -0.4064)
			(stroke
				(width 0.1524)
				(type default)
			)
			(layer "B.SilkS")
		)
		(fp_line
			(start -0.7874 0.4064)
			(end 0.7874 0.4064)
			(stroke
				(width 0.1524)
				(type default)
			)
			(layer "B.SilkS")
		)
		(fp_line
			(start 0.67945 -0.305054)
			(end 0.12065 -0.305054)
			(stroke
				(width 0.1)
				(type default)
			)
			(layer "B.Fab")
		)
		(fp_line
			(start 0.12065 -0.305054)
			(end 0.12065 -0.2794)
			(stroke
				(width 0.1)
				(type default)
			)
			(layer "B.Fab")
		)
		(fp_line
			(start -0.12065 -0.3048)
			(end -0.67945 -0.3048)
			(stroke
				(width 0.1)
				(type default)
			)
			(layer "B.Fab")
		)
		(fp_line
			(start -0.67945 -0.3048)
			(end -0.67945 0.3048)
			(stroke
				(width 0.1)
				(type default)
			)
			(layer "B.Fab")
		)
		(fp_line
			(start 0.12065 -0.2794)
			(end -0.12065 -0.2794)
			(stroke
				(width 0.1)
				(type default)
			)
			(layer "B.Fab")
		)
		(fp_line
			(start -0.12065 -0.2794)
			(end -0.12065 -0.3048)
			(stroke
				(width 0.1)
				(type default)
			)
			(layer "B.Fab")
		)
		(fp_line
			(start 0.12065 0.2794)
			(end 0.12065 0.3048)
			(stroke
				(width 0.1)
				(type default)
			)
			(layer "B.Fab")
		)
		(fp_line
			(start -0.120396 0.2794)
			(end 0.12065 0.2794)
			(stroke
				(width 0.1)
				(type default)
			)
			(layer "B.Fab")
		)
		(fp_line
			(start 0.67945 0.3048)
			(end 0.67945 -0.305054)
			(stroke
				(width 0.1)
				(type default)
			)
			(layer "B.Fab")
		)
		(fp_line
			(start 0.12065 0.3048)
			(end 0.67945 0.3048)
			(stroke
				(width 0.1)
				(type default)
			)
			(layer "B.Fab")
		)
		(fp_line
			(start -0.120396 0.3048)
			(end -0.120396 0.2794)
			(stroke
				(width 0.1)
				(type default)
			)
			(layer "B.Fab")
		)
		(fp_line
			(start -0.67945 0.3048)
			(end -0.120396 0.3048)
			(stroke
				(width 0.1)
				(type default)
			)
			(layer "B.Fab")
		)
		(pad "1" smd circle
			(at 0.40005 0 270)
			(size 0 0)
			(layers "B.Cu" "B.Mask" "B.Paste")
			(net "FM_PCH_P1V8_AUX_EN")
		)
		(pad "2" smd circle
			(at -0.40005 0 270)
			(size 0 0)
			(layers "B.Cu" "B.Mask" "B.Paste")
			(net "FM_PCH_P1V8_AUX_EN_R")
		)
	)
	(footprint ""
		(layer "B.Cu")
		(at 458.42428 -319.132204)
		(property "Reference" "C44"
			(at 0 0 0)
			(layer "B.SilkS")
			(hide yes)
			(effects
				(font
					(size 1.27 1.27)
				)
				(justify mirror)
			)
		)
		(property "Value" ""
			(at 0 0 0)
			(layer "B.Fab")
			(effects
				(font
					(size 1.27 1.27)
				)
				(justify mirror)
			)
		)
		(duplicate_pad_numbers_are_jumpers no)
		(fp_line
			(start -0.7874 -0.4064)
			(end -0.7874 0.4064)
			(stroke
				(width 0.1524)
				(type default)
			)
			(layer "B.SilkS")
		)
		(fp_line
			(start -0.7874 0.4064)
			(end 0.7874 0.4064)
			(stroke
				(width 0.1524)
				(type default)
			)
			(layer "B.SilkS")
		)
		(fp_line
			(start 0.7874 -0.4064)
			(end -0.7874 -0.4064)
			(stroke
				(width 0.1524)
				(type default)
			)
			(layer "B.SilkS")
		)
		(fp_line
			(start 0.7874 0.4064)
			(end 0.7874 -0.4064)
			(stroke
				(width 0.1524)
				(type default)
			)
			(layer "B.SilkS")
		)
		(fp_line
			(start -0.67945 -0.3048)
			(end -0.67945 0.3048)
			(stroke
				(width 0.1)
				(type default)
			)
			(layer "B.Fab")
		)
		(fp_line
			(start -0.67945 0.3048)
			(end -0.120396 0.3048)
			(stroke
				(width 0.1)
				(type default)
			)
			(layer "B.Fab")
		)
		(fp_line
			(start -0.12065 -0.3048)
			(end -0.67945 -0.3048)
			(stroke
				(width 0.1)
				(type default)
			)
			(layer "B.Fab")
		)
		(fp_line
			(start -0.12065 -0.2794)
			(end -0.12065 -0.3048)
			(stroke
				(width 0.1)
				(type default)
			)
			(layer "B.Fab")
		)
		(fp_line
			(start -0.120396 0.2794)
			(end 0.12065 0.2794)
			(stroke
				(width 0.1)
				(type default)
			)
			(layer "B.Fab")
		)
		(fp_line
			(start -0.120396 0.3048)
			(end -0.120396 0.2794)
			(stroke
				(width 0.1)
				(type default)
			)
			(layer "B.Fab")
		)
		(fp_line
			(start 0.12065 -0.305054)
			(end 0.12065 -0.2794)
			(stroke
				(width 0.1)
				(type default)
			)
			(layer "B.Fab")
		)
		(fp_line
			(start 0.12065 -0.2794)
			(end -0.12065 -0.2794)
			(stroke
				(width 0.1)
				(type default)
			)
			(layer "B.Fab")
		)
		(fp_line
			(start 0.12065 0.2794)
			(end 0.12065 0.3048)
			(stroke
				(width 0.1)
				(type default)
			)
			(layer "B.Fab")
		)
		(fp_line
			(start 0.12065 0.3048)
			(end 0.67945 0.3048)
			(stroke
				(width 0.1)
				(type default)
			)
			(layer "B.Fab")
		)
		(fp_line
			(start 0.67945 -0.305054)
			(end 0.12065 -0.305054)
			(stroke
				(width 0.1)
				(type default)
			)
			(layer "B.Fab")
		)
		(fp_line
			(start 0.67945 0.3048)
			(end 0.67945 -0.305054)
			(stroke
				(width 0.1)
				(type default)
			)
			(layer "B.Fab")
		)
		(pad "1" smd circle
			(at 0.40005 0 180)
			(size 0 0)
			(layers "B.Cu" "B.Mask" "B.Paste")
			(net "P3V3_AUX")
		)
		(pad "2" smd circle
			(at -0.40005 0 180)
			(size 0 0)
			(layers "B.Cu" "B.Mask" "B.Paste")
			(net "GND")
		)
	)
	(footprint ""
		(layer "B.Cu")
		(at 422.5163 -154.262328)
		(property "Reference" "PR4227"
			(at 0 0 0)
			(layer "B.SilkS")
			(hide yes)
			(effects
				(font
					(size 1.27 1.27)
				)
				(justify mirror)
			)
		)
		(property "Value" ""
			(at 0 0 0)
			(layer "B.Fab")
			(effects
				(font
					(size 1.27 1.27)
				)
				(justify mirror)
			)
		)
		(duplicate_pad_numbers_are_jumpers no)
		(fp_line
			(start -0.7874 -0.4064)
			(end -0.7874 0.4064)
			(stroke
				(width 0.1524)
				(type default)
			)
			(layer "B.SilkS")
		)
		(fp_line
			(start -0.7874 0.4064)
			(end 0.7874 0.4064)
			(stroke
				(width 0.1524)
				(type default)
			)
			(layer "B.SilkS")
		)
		(fp_line
			(start 0.7874 -0.4064)
			(end -0.7874 -0.4064)
			(stroke
				(width 0.1524)
				(type default)
			)
			(layer "B.SilkS")
		)
		(fp_line
			(start 0.7874 0.4064)
			(end 0.7874 -0.4064)
			(stroke
				(width 0.1524)
				(type default)
			)
			(layer "B.SilkS")
		)
		(fp_line
			(start -0.67945 -0.3048)
			(end -0.67945 0.3048)
			(stroke
				(width 0.1)
				(type default)
			)
			(layer "B.Fab")
		)
		(fp_line
			(start -0.67945 0.3048)
			(end -0.120396 0.3048)
			(stroke
				(width 0.1)
				(type default)
			)
			(layer "B.Fab")
		)
		(fp_line
			(start -0.12065 -0.3048)
			(end -0.67945 -0.3048)
			(stroke
				(width 0.1)
				(type default)
			)
			(layer "B.Fab")
		)
		(fp_line
			(start -0.12065 -0.2794)
			(end -0.12065 -0.3048)
			(stroke
				(width 0.1)
				(type default)
			)
			(layer "B.Fab")
		)
		(fp_line
			(start -0.120396 0.2794)
			(end 0.12065 0.2794)
			(stroke
				(width 0.1)
				(type default)
			)
			(layer "B.Fab")
		)
		(fp_line
			(start -0.120396 0.3048)
			(end -0.120396 0.2794)
			(stroke
				(width 0.1)
				(type default)
			)
			(layer "B.Fab")
		)
		(fp_line
			(start 0.12065 -0.305054)
			(end 0.12065 -0.2794)
			(stroke
				(width 0.1)
				(type default)
			)
			(layer "B.Fab")
		)
		(fp_line
			(start 0.12065 -0.2794)
			(end -0.12065 -0.2794)
			(stroke
				(width 0.1)
				(type default)
			)
			(layer "B.Fab")
		)
		(fp_line
			(start 0.12065 0.2794)
			(end 0.12065 0.3048)
			(stroke
				(width 0.1)
				(type default)
			)
			(layer "B.Fab")
		)
		(fp_line
			(start 0.12065 0.3048)
			(end 0.67945 0.3048)
			(stroke
				(width 0.1)
				(type default)
			)
			(layer "B.Fab")
		)
		(fp_line
			(start 0.67945 -0.305054)
			(end 0.12065 -0.305054)
			(stroke
				(width 0.1)
				(type default)
			)
			(layer "B.Fab")
		)
		(fp_line
			(start 0.67945 0.3048)
			(end 0.67945 -0.305054)
			(stroke
				(width 0.1)
				(type default)
			)
			(layer "B.Fab")
		)
		(pad "1" smd circle
			(at 0.40005 0 180)
			(size 0 0)
			(layers "B.Cu" "B.Mask" "B.Paste")
			(net "PVCCFA_EHV_CPU0_VDD1")
		)
		(pad "2" smd circle
			(at -0.40005 0 180)
			(size 0 0)
			(layers "B.Cu" "B.Mask" "B.Paste")
			(net "PVCCFA_EHV_CPU0_NC2")
		)
	)
)
